# S9S_MB_2U (Grand Teton) — schematic netlist excerpt (pin names and nets, part order shuffled) for the footprints in the layout excerpt that follows; sources: Cadence DE-HDL packaged netlist, KiCad conversion of 03242023_DA0F0TMBIJ0_F0T_Motherboard_J_brd_V01_OCP.brd

U36  TCA9548APWR  IC  pkg TSSOP24XA  page 231
  A0  = PCA9548_PCIE3_ADDR0
  A1  = PCA9548_PCIE3_ADDR1
  \reset#\  = PU_RST_SMB_PCIE0_N
  SD0  = NC
  SC0  = NC
  SD1  = SMB_IOEXP_3V3AUX_SDA_R
  SC1  = SMB_IOEXP_3V3AUX_SCL_R
  SD2  = SMB_PCIE0_3V3AUX_SDA_R3
  SC2  = SMB_PCIE0_3V3AUX_SCL_R3
  SD3  = SMB_PCIE0_3V3AUX_SDA_R5
  SC3  = SMB_PCIE0_3V3AUX_SCL_R5
  GND  = GND
  SD4  = SMB_BMC_SWB_SDA_R4
  SC4  = SMB_BMC_SWB_SCL_R4
  SD5  = SMB_FRU_3V3AUX_SDA_R
  SC5  = SMB_FRU_3V3AUX_SCL_R
  SD6  = SMB_INA230_3V3AUX_SDA_R
  SC6  = SMB_INA230_3V3AUX_SCL_R
  SD7  = NC
  SC7  = NC
  A2  = PCA9548_PCIE3_ADDR2
  SCL  = SMB_PCIE0_3V3AUX_SCL_R
  SDA  = SMB_PCIE0_3V3AUX_SDA_R
  VCC  = P3V3_AUX

(kicad_pcb
	(version 20260206)
	(generator "pcbnew")
	(generator_version "10.0")
	(general
		(thickness 1.6)
		(legacy_teardrops no)
	)
	(paper "A4")
	(title_block
		(title "03242023_DA0F0TMBIJ0_F0T_Motherboard_J_brd_V01_OCP.brd")
		(comment 1 "Grand Teton / footprints 2074-2074 of 6105")
	)
	(layers
		(0 "F.Cu" signal "TOP")
		(4 "In1.Cu" signal "GND")
		(6 "In2.Cu" signal "IN1")
		(8 "In3.Cu" signal "GND1")
		(10 "In4.Cu" signal "IN2")
		(12 "In5.Cu" signal "GND2")
		(14 "In6.Cu" signal "IN3")
		(16 "In7.Cu" signal "GND3")
		(18 "In8.Cu" signal "VCC")
		(20 "In9.Cu" signal "VCC1")
		(22 "In10.Cu" signal "GND4")
		(24 "In11.Cu" signal "IN4")
		(26 "In12.Cu" signal "GND5")
		(28 "In13.Cu" signal "IN5")
		(30 "In14.Cu" signal "GND6")
		(32 "In15.Cu" signal "IN6")
		(34 "In16.Cu" signal "GND7")
		(2 "B.Cu" signal "BOTTOM")
		(9 "F.Adhes" user "F.Adhesive")
		(11 "B.Adhes" user "B.Adhesive")
		(13 "F.Paste" user "Package Geometry/Pastemask Top")
		(15 "B.Paste" user "Package Geometry/Pastemask Bottom")
		(5 "F.SilkS" user "Ref Des/Silkscreen Top")
		(7 "B.SilkS" user "Ref Des/Silkscreen Bottom")
		(1 "F.Mask" user "Board Geometry/Soldermask Top")
		(3 "B.Mask" user "Board Geometry/Soldermask Bottom")
		(17 "Dwgs.User" user "User.Drawings")
		(19 "Cmts.User" user "User.Comments")
		(21 "Eco1.User" user "User.Eco1")
		(23 "Eco2.User" user "User.Eco2")
		(25 "Edge.Cuts" user "Board Geometry/Outline")
		(27 "Margin" user)
		(31 "F.CrtYd" user "Package Geometry/Place Bound Top")
		(29 "B.CrtYd" user "Package Geometry/Place Bound Bottom")
		(35 "F.Fab" user "Ref Des/Assembly Top")
		(33 "B.Fab" user "Ref Des/Assembly Bottom")
	)
	(footprint ""
		(layer "F.Cu")
		(at 120.908572 -133.971538)
		(property "Reference" "U36"
			(at -2.1844 -4.587748 0)
			(unlocked yes)
			(layer "F.SilkS")
			(effects
				(font
					(size 0.7874 0.5842)
					(thickness 0.1524)
				)
				(justify left)
			)
		)
		(property "Value" ""
			(at 0 0 0)
			(layer "F.Fab")
			(effects
				(font
					(size 1.27 1.27)
				)
			)
		)
		(duplicate_pad_numbers_are_jumpers no)
		(fp_line
			(start -1.8542 -3.949954)
			(end -1.8542 3.949954)
			(stroke
				(width 0.1524)
				(type default)
			)
			(layer "F.SilkS")
		)
		(fp_line
			(start -1.8542 3.949954)
			(end 1.8542 3.949954)
			(stroke
				(width 0.1524)
				(type default)
			)
			(layer "F.SilkS")
		)
		(fp_line
			(start -1.282954 -3.949954)
			(end -1.8542 -3.949954)
			(stroke
				(width 0.1524)
				(type default)
			)
			(layer "F.SilkS")
		)
		(fp_line
			(start 0 -2.667)
			(end -1.282954 -3.949954)
			(stroke
				(width 0.1524)
				(type default)
			)
			(layer "F.SilkS")
		)
		(fp_line
			(start 1.282954 -3.949954)
			(end 0 -2.667)
			(stroke
				(width 0.1524)
				(type default)
			)
			(layer "F.SilkS")
		)
		(fp_line
			(start 1.8542 -3.949954)
			(end 1.282954 -3.949954)
			(stroke
				(width 0.1524)
				(type default)
			)
			(layer "F.SilkS")
		)
		(fp_line
			(start 1.8542 3.949954)
			(end 1.8542 -3.949954)
			(stroke
				(width 0.1524)
				(type default)
			)
			(layer "F.SilkS")
		)
		(fp_poly
			(pts
				(xy -4.8006 -4.08305) (xy -4.8006 -3.06705) (xy -3.7846 -3.57505)
			)
			(stroke
				(width 0)
				(type default)
			)
			(fill yes)
			(layer "F.SilkS")
		)
		(fp_line
			(start -2.249932 -3.949954)
			(end -2.249932 3.949954)
			(stroke
				(width 0.1)
				(type default)
			)
			(layer "F.Fab")
		)
		(fp_line
			(start -2.249932 3.949954)
			(end 2.249932 3.949954)
			(stroke
				(width 0.1)
				(type default)
			)
			(layer "F.Fab")
		)
		(fp_line
			(start 2.249932 -3.949954)
			(end -2.249932 -3.949954)
			(stroke
				(width 0.1)
				(type default)
			)
			(layer "F.Fab")
		)
		(fp_line
			(start 2.249932 3.949954)
			(end 2.249932 -3.949954)
			(stroke
				(width 0.1)
				(type default)
			)
			(layer "F.Fab")
		)
		(fp_poly
			(pts
				(xy -4.8006 -4.08305) (xy -4.8006 -3.06705) (xy -3.7846 -3.57505)
			)
			(stroke
				(width 0)
				(type default)
			)
			(fill yes)
			(layer "F.Fab")
		)
		(pad "1" smd rect
			(at -2.800096 -3.57505 270)
			(size 0.3048 1.6002)
			(layers "F.Cu" "F.Mask" "F.Paste")
			(net "PCA9548_PCIE3_ADDR0")
		)
		(pad "2" smd rect
			(at -2.800096 -2.925064 270)
			(size 0.3048 1.6002)
			(layers "F.Cu" "F.Mask" "F.Paste")
			(net "PCA9548_PCIE3_ADDR1")
		)
		(pad "3" smd rect
			(at -2.800096 -2.275078 270)
			(size 0.3048 1.6002)
			(layers "F.Cu" "F.Mask" "F.Paste")
			(net "PU_RST_SMB_PCIE0_N")
		)
		(pad "4" smd rect
			(at -2.800096 -1.625092 270)
			(size 0.3048 1.6002)
			(layers "F.Cu" "F.Mask" "F.Paste")
			(net "Net_283")
		)
		(pad "5" smd rect
			(at -2.800096 -0.975106 270)
			(size 0.3048 1.6002)
			(layers "F.Cu" "F.Mask" "F.Paste")
			(net "Net_281")
		)
		(pad "6" smd rect
			(at -2.800096 -0.32512 270)
			(size 0.3048 1.6002)
			(layers "F.Cu" "F.Mask" "F.Paste")
			(net "SMB_IOEXP_3V3AUX_SDA_R")
		)
		(pad "7" smd rect
			(at -2.800096 0.32512 270)
			(size 0.3048 1.6002)
			(layers "F.Cu" "F.Mask" "F.Paste")
			(net "SMB_IOEXP_3V3AUX_SCL_R")
		)
		(pad "8" smd rect
			(at -2.800096 0.975106 270)
			(size 0.3048 1.6002)
			(layers "F.Cu" "F.Mask" "F.Paste")
			(net "SMB_PCIE0_3V3AUX_SDA_R3")
		)
		(pad "9" smd rect
			(at -2.800096 1.625092 270)
			(size 0.3048 1.6002)
			(layers "F.Cu" "F.Mask" "F.Paste")
			(net "SMB_PCIE0_3V3AUX_SCL_R3")
		)
		(pad "10" smd rect
			(at -2.800096 2.275078 270)
			(size 0.3048 1.6002)
			(layers "F.Cu" "F.Mask" "F.Paste")
			(net "SMB_PCIE0_3V3AUX_SDA_R5")
		)
		(pad "11" smd rect
			(at -2.800096 2.925064 270)
			(size 0.3048 1.6002)
			(layers "F.Cu" "F.Mask" "F.Paste")
			(net "SMB_PCIE0_3V3AUX_SCL_R5")
		)
		(pad "12" smd rect
			(at -2.800096 3.57505 270)
			(size 0.3048 1.6002)
			(layers "F.Cu" "F.Mask" "F.Paste")
			(net "GND")
		)
		(pad "13" smd rect
			(at 2.800096 3.57505 270)
			(size 0.3048 1.6002)
			(layers "F.Cu" "F.Mask" "F.Paste")
			(net "SMB_BMC_SWB_SDA_R4")
		)
		(pad "14" smd rect
			(at 2.800096 2.925064 270)
			(size 0.3048 1.6002)
			(layers "F.Cu" "F.Mask" "F.Paste")
			(net "SMB_BMC_SWB_SCL_R4")
		)
		(pad "15" smd rect
			(at 2.800096 2.275078 270)
			(size 0.3048 1.6002)
			(layers "F.Cu" "F.Mask" "F.Paste")
			(net "SMB_FRU_3V3AUX_SDA_R")
		)
		(pad "16" smd rect
			(at 2.800096 1.625092 270)
			(size 0.3048 1.6002)
			(layers "F.Cu" "F.Mask" "F.Paste")
			(net "SMB_FRU_3V3AUX_SCL_R")
		)
		(pad "17" smd rect
			(at 2.800096 0.975106 270)
			(size 0.3048 1.6002)
			(layers "F.Cu" "F.Mask" "F.Paste")
			(net "SMB_INA230_3V3AUX_SDA_R")
		)
		(pad "18" smd rect
			(at 2.800096 0.32512 270)
			(size 0.3048 1.6002)
			(layers "F.Cu" "F.Mask" "F.Paste")
			(net "SMB_INA230_3V3AUX_SCL_R")
		)
		(pad "19" smd rect
			(at 2.800096 -0.32512 270)
			(size 0.3048 1.6002)
			(layers "F.Cu" "F.Mask" "F.Paste")
			(net "Net_284")
		)
		(pad "20" smd rect
			(at 2.800096 -0.975106 270)
			(size 0.3048 1.6002)
			(layers "F.Cu" "F.Mask" "F.Paste")
			(net "Net_282")
		)
		(pad "21" smd rect
			(at 2.800096 -1.625092 270)
			(size 0.3048 1.6002)
			(layers "F.Cu" "F.Mask" "F.Paste")
			(net "PCA9548_PCIE3_ADDR2")
		)
		(pad "22" smd rect
			(at 2.800096 -2.275078 270)
			(size 0.3048 1.6002)
			(layers "F.Cu" "F.Mask" "F.Paste")
			(net "SMB_PCIE0_3V3AUX_SCL_R")
		)
		(pad "23" smd rect
			(at 2.800096 -2.925064 270)
			(size 0.3048 1.6002)
			(layers "F.Cu" "F.Mask" "F.Paste")
			(net "SMB_PCIE0_3V3AUX_SDA_R")
		)
		(pad "24" smd rect
			(at 2.800096 -3.57505 270)
			(size 0.3048 1.6002)
			(layers "F.Cu" "F.Mask" "F.Paste")
			(net "P3V3_AUX")
		)
	)
)
